#ISCELL
  pure_quanta quanta_title_block_c *
  *
#ISCELL
  standard offpage *
  page13_i10
#ISCELL
  standard offpage *
  page13_i11
#ISCELL
  standard offpage *
  page13_i12
#ISCELL
  standard offpage *
  page13_i13
#ISCELL
  standard offpage *
  page13_i14
#ISCELL
  standard offpage *
  page13_i15
#CELL
  pure_quanta q_res *
  page13_i16
#ISCELL
  standard offpage *
  page13_i17
#CELL
  pure_quanta q_res *
  page13_i18
#ISCELL
  standard offpage *
  page13_i19
#ISCELL
  standard offpage *
  page13_i2
#CELL
  pure_quanta q_res *
  page13_i21
#ISCELL
  standard offpage *
  page13_i22
#ISCELL
  standard offpage *
  page13_i23
#CELL
  pure_quanta q_res *
  page13_i24
#CELL
  pure_quanta q_res *
  page13_i25
#ISCELL
  standard offpage *
  page13_i26
#ISCELL
  standard offpage *
  page13_i28
#CELL
  pure_quanta q_res *
  page13_i29
#ISCELL
  standard offpage *
  page13_i3
#ISCELL
  standard offpage *
  page13_i30
#ISCELL
  standard offpage *
  page13_i31
#ISCELL
  standard offpage *
  page13_i32
#ISCELL
  standard offpage *
  page13_i33
#ISCELL
  standard offpage *
  page13_i34
#ISCELL
  standard offpage *
  page13_i35
#ISCELL
  standard offpage *
  page13_i36
#ISCELL
  standard offpage *
  page13_i37
#ISCELL
  standard offpage *
  page13_i38
#ISCELL
  standard offpage *
  page13_i39
#ISCELL
  standard offpage *
  page13_i4
#ISCELL
  standard offpage *
  page13_i40
#ISCELL
  standard offpage *
  page13_i41
#ISCELL
  standard offpage *
  page13_i42
#ISCELL
  standard offpage *
  page13_i43
#ISCELL
  standard offpage *
  page13_i44
#ISCELL
  standard offpage *
  page13_i45
#ISCELL
  standard offpage *
  page13_i5
#ISCELL
  standard offpage *
  page13_i51
#ISCELL
  standard offpage *
  page13_i53
#ISCELL
  standard offpage *
  page13_i54
#ISCELL
  standard offpage *
  page13_i55
#ISCELL
  standard offpage *
  page13_i56
#CELL
  pure_quanta socket4677_azif0045p001c01cs *
  page13_i57
#ISCELL
  standard offpage *
  page13_i58
#ISCELL
  standard offpage *
  page13_i59
#ISCELL
  standard offpage *
  page13_i6
#ISCELL
  standard offpage *
  page13_i60
#ISCELL
  standard offpage *
  page13_i7
#ISCELL
  standard offpage *
  page13_i8
#ISCELL
  standard offpage *
  page13_i9
